(kicad_pcb
	(version 20241229)
	(generator "pcbnew")
	(generator_version "9.0")
	(general
		(thickness 1.599998)
		(legacy_teardrops no)
	)
	(paper "A4")
	(title_block
		(title "Artix - Datacenter Secure Control Module (DC-SCM)")
		(date "2024-11-06")
		(rev "1.1.3")
		(comment 9 "footprints 309-313 of 544")
	)
	(layers
		(0 "F.Cu" signal)
		(4 "In1.Cu" signal)
		(6 "In2.Cu" signal)
		(8 "In3.Cu" signal)
		(10 "In4.Cu" signal)
		(12 "In5.Cu" signal)
		(14 "In6.Cu" signal)
		(2 "B.Cu" signal)
		(9 "F.Adhes" user "F.Adhesive")
		(11 "B.Adhes" user "B.Adhesive")
		(13 "F.Paste" user)
		(15 "B.Paste" user)
		(5 "F.SilkS" user "F.Silkscreen")
		(7 "B.SilkS" user "B.Silkscreen")
		(1 "F.Mask" user)
		(3 "B.Mask" user)
		(17 "Dwgs.User" user "User.Drawings")
		(19 "Cmts.User" user "User.Comments")
		(21 "Eco1.User" user "User.Eco1")
		(23 "Eco2.User" user "User.Eco2")
		(25 "Edge.Cuts" user)
		(27 "Margin" user)
		(31 "F.CrtYd" user "F.Courtyard")
		(29 "B.CrtYd" user "B.Courtyard")
		(35 "F.Fab" user)
		(33 "B.Fab" user)
	)
	(footprint "antmicro-footprints:C_0402_1005Metric"
		(layer "B.Cu")
		(at 111.275 112.575 -90)
		(descr "Capacitor SMD 0402")
		(tags "capacitor SMD 0402")
		(property "Reference" "C121"
			(at -1.375 -1.225 90)
			(layer "B.SilkS")
			(effects
				(font
					(size 0.7 0.7)
					(thickness 0.15)
				)
				(justify left bottom mirror)
			)
		)
		(property "Value" "C_470n_0402"
			(at 0 -1.4 90)
			(layer "B.Fab")
			(effects
				(font
					(size 0.7 0.7)
					(thickness 0.15)
				)
				(justify left bottom mirror)
			)
		)
		(property "Datasheet" "https://product.tdk.com/en/search/capacitor/ceramic/mlcc/info?part_no=C1005X5R1E474M050BB"
			(at 0 0 270)
			(layer "F.Fab")
			(hide yes)
			(effects
				(font
					(size 1.27 1.27)
					(thickness 0.15)
				)
			)
		)
		(property "Description" "SMD Multilayer Ceramic Capacitor, 0.47 µF, 25 V, 0402 [1005 Metric], ± 20%, X5R, C"
			(at 0 0 270)
			(layer "F.Fab")
			(hide yes)
			(effects
				(font
					(size 1.27 1.27)
					(thickness 0.15)
				)
			)
		)
		(property "Author" "Antmicro"
			(at -1.3 223.85 0)
			(layer "B.Fab")
			(hide yes)
			(effects
				(font
					(size 1 1)
					(thickness 0.15)
				)
				(justify mirror)
			)
		)
		(property "Dielectric" ""
			(at -1.3 223.85 0)
			(layer "B.Fab")
			(hide yes)
			(effects
				(font
					(size 1 1)
					(thickness 0.15)
				)
				(justify mirror)
			)
		)
		(property "License" "Apache-2.0"
			(at -1.3 223.85 0)
			(layer "B.Fab")
			(hide yes)
			(effects
				(font
					(size 1 1)
					(thickness 0.15)
				)
				(justify mirror)
			)
		)
		(property "MPN" "C1005X5R1E474M050BB"
			(at -1.3 223.85 0)
			(layer "B.Fab")
			(hide yes)
			(effects
				(font
					(size 1 1)
					(thickness 0.15)
				)
				(justify mirror)
			)
		)
		(property "Manufacturer" "TDK"
			(at -1.3 223.85 0)
			(layer "B.Fab")
			(hide yes)
			(effects
				(font
					(size 1 1)
					(thickness 0.15)
				)
				(justify mirror)
			)
		)
		(property "Val" "470n"
			(at -1.3 223.85 0)
			(layer "B.Fab")
			(hide yes)
			(effects
				(font
					(size 1 1)
					(thickness 0.15)
				)
				(justify mirror)
			)
		)
		(property "Voltage" ""
			(at -1.3 223.85 0)
			(layer "B.Fab")
			(hide yes)
			(effects
				(font
					(size 1 1)
					(thickness 0.15)
				)
				(justify mirror)
			)
		)
		(sheetname "/FPGA banks 34-35 & CFG/")
		(sheetfile "fpga-banks-34-25-cfg.kicad_sch")
		(attr smd)
		(fp_rect
			(start -0.925 0.47)
			(end 0.925 -0.47)
			(stroke
				(width 0.05)
				(type default)
			)
			(fill no)
			(layer "B.CrtYd")
		)
		(fp_line
			(start -0.494 0.25)
			(end 0.504 0.25)
			(stroke
				(width 0.15)
				(type solid)
			)
			(layer "B.Fab")
		)
		(fp_line
			(start 0.504 0.25)
			(end 0.504 -0.248)
			(stroke
				(width 0.15)
				(type solid)
			)
			(layer "B.Fab")
		)
		(fp_line
			(start -0.494 -0.248)
			(end -0.494 0.25)
			(stroke
				(width 0.15)
				(type solid)
			)
			(layer "B.Fab")
		)
		(fp_line
			(start 0.504 -0.248)
			(end -0.494 -0.248)
			(stroke
				(width 0.15)
				(type solid)
			)
			(layer "B.Fab")
		)
		(pad "1" smd roundrect
			(at -0.48 0 270)
			(size 0.59 0.64)
			(layers "B.Cu" "B.Mask" "B.Paste")
			(roundrect_rratio 0.25)
			(net 1 "GND")
			(pintype "passive")
		)
		(pad "2" smd roundrect
			(at 0.48 0 270)
			(size 0.59 0.64)
			(layers "B.Cu" "B.Mask" "B.Paste")
			(roundrect_rratio 0.25)
			(net 2 "VCC3V3")
			(pintype "passive")
		)
	)
	(footprint "antmicro-footprints:C_0402_1005Metric"
		(layer "B.Cu")
		(at 109.275 118.675 180)
		(descr "Capacitor SMD 0402")
		(tags "capacitor SMD 0402")
		(property "Reference" "C127"
			(at -3.623 -0.425 0)
			(layer "B.SilkS")
			(effects
				(font
					(size 0.7 0.7)
					(thickness 0.15)
				)
				(justify left bottom mirror)
			)
		)
		(property "Value" "C_470n_0402"
			(at 0 -1.4 0)
			(layer "B.Fab")
			(effects
				(font
					(size 0.7 0.7)
					(thickness 0.15)
				)
				(justify left bottom mirror)
			)
		)
		(property "Datasheet" "https://product.tdk.com/en/search/capacitor/ceramic/mlcc/info?part_no=C1005X5R1E474M050BB"
			(at 0 0 180)
			(layer "F.Fab")
			(hide yes)
			(effects
				(font
					(size 1.27 1.27)
					(thickness 0.15)
				)
			)
		)
		(property "Description" "SMD Multilayer Ceramic Capacitor, 0.47 µF, 25 V, 0402 [1005 Metric], ± 20%, X5R, C"
			(at 0 0 180)
			(layer "F.Fab")
			(hide yes)
			(effects
				(font
					(size 1.27 1.27)
					(thickness 0.15)
				)
			)
		)
		(property "Author" "Antmicro"
			(at 218.55 237.35 0)
			(layer "B.Fab")
			(hide yes)
			(effects
				(font
					(size 1 1)
					(thickness 0.15)
				)
				(justify mirror)
			)
		)
		(property "Dielectric" ""
			(at 218.55 237.35 0)
			(layer "B.Fab")
			(hide yes)
			(effects
				(font
					(size 1 1)
					(thickness 0.15)
				)
				(justify mirror)
			)
		)
		(property "License" "Apache-2.0"
			(at 218.55 237.35 0)
			(layer "B.Fab")
			(hide yes)
			(effects
				(font
					(size 1 1)
					(thickness 0.15)
				)
				(justify mirror)
			)
		)
		(property "MPN" "C1005X5R1E474M050BB"
			(at 218.55 237.35 0)
			(layer "B.Fab")
			(hide yes)
			(effects
				(font
					(size 1 1)
					(thickness 0.15)
				)
				(justify mirror)
			)
		)
		(property "Manufacturer" "TDK"
			(at 218.55 237.35 0)
			(layer "B.Fab")
			(hide yes)
			(effects
				(font
					(size 1 1)
					(thickness 0.15)
				)
				(justify mirror)
			)
		)
		(property "Val" "470n"
			(at 218.55 237.35 0)
			(layer "B.Fab")
			(hide yes)
			(effects
				(font
					(size 1 1)
					(thickness 0.15)
				)
				(justify mirror)
			)
		)
		(property "Voltage" ""
			(at 218.55 237.35 0)
			(layer "B.Fab")
			(hide yes)
			(effects
				(font
					(size 1 1)
					(thickness 0.15)
				)
				(justify mirror)
			)
		)
		(sheetname "/FPGA banks 34-35 & CFG/")
		(sheetfile "fpga-banks-34-25-cfg.kicad_sch")
		(attr smd)
		(fp_rect
			(start -0.925 0.47)
			(end 0.925 -0.47)
			(stroke
				(width 0.05)
				(type default)
			)
			(fill no)
			(layer "B.CrtYd")
		)
		(fp_line
			(start 0.504 0.25)
			(end 0.504 -0.248)
			(stroke
				(width 0.15)
				(type solid)
			)
			(layer "B.Fab")
		)
		(fp_line
			(start 0.504 -0.248)
			(end -0.494 -0.248)
			(stroke
				(width 0.15)
				(type solid)
			)
			(layer "B.Fab")
		)
		(fp_line
			(start -0.494 0.25)
			(end 0.504 0.25)
			(stroke
				(width 0.15)
				(type solid)
			)
			(layer "B.Fab")
		)
		(fp_line
			(start -0.494 -0.248)
			(end -0.494 0.25)
			(stroke
				(width 0.15)
				(type solid)
			)
			(layer "B.Fab")
		)
		(pad "1" smd roundrect
			(at -0.48 0 180)
			(size 0.59 0.64)
			(layers "B.Cu" "B.Mask" "B.Paste")
			(roundrect_rratio 0.25)
			(net 1 "GND")
			(pintype "passive")
		)
		(pad "2" smd roundrect
			(at 0.48 0 180)
			(size 0.59 0.64)
			(layers "B.Cu" "B.Mask" "B.Paste")
			(roundrect_rratio 0.25)
			(net 2 "VCC3V3")
			(pintype "passive")
		)
	)
	(footprint "antmicro-footprints:C_0402_1005Metric"
		(layer "B.Cu")
		(at 104.275 115.675)
		(descr "Capacitor SMD 0402")
		(tags "capacitor SMD 0402")
		(property "Reference" "C110"
			(at -4.075 0.925 0)
			(layer "B.SilkS")
			(effects
				(font
					(size 0.7 0.7)
					(thickness 0.15)
				)
				(justify right bottom mirror)
			)
		)
		(property "Value" "C_470n_0402"
			(at 0 -1.4 0)
			(layer "B.Fab")
			(effects
				(font
					(size 0.7 0.7)
					(thickness 0.15)
				)
				(justify right bottom mirror)
			)
		)
		(property "Datasheet" "https://product.tdk.com/en/search/capacitor/ceramic/mlcc/info?part_no=C1005X5R1E474M050BB"
			(at 0 0 0)
			(layer "F.Fab")
			(hide yes)
			(effects
				(font
					(size 1.27 1.27)
					(thickness 0.15)
				)
			)
		)
		(property "Description" "SMD Multilayer Ceramic Capacitor, 0.47 µF, 25 V, 0402 [1005 Metric], ± 20%, X5R, C"
			(at 0 0 0)
			(layer "F.Fab")
			(hide yes)
			(effects
				(font
					(size 1.27 1.27)
					(thickness 0.15)
				)
			)
		)
		(property "Author" "Antmicro"
			(at 0 0 0)
			(layer "B.Fab")
			(hide yes)
			(effects
				(font
					(size 1 1)
					(thickness 0.15)
				)
				(justify mirror)
			)
		)
		(property "Dielectric" ""
			(at 0 0 0)
			(layer "B.Fab")
			(hide yes)
			(effects
				(font
					(size 1 1)
					(thickness 0.15)
				)
				(justify mirror)
			)
		)
		(property "License" "Apache-2.0"
			(at 0 0 0)
			(layer "B.Fab")
			(hide yes)
			(effects
				(font
					(size 1 1)
					(thickness 0.15)
				)
				(justify mirror)
			)
		)
		(property "MPN" "C1005X5R1E474M050BB"
			(at 0 0 0)
			(layer "B.Fab")
			(hide yes)
			(effects
				(font
					(size 1 1)
					(thickness 0.15)
				)
				(justify mirror)
			)
		)
		(property "Manufacturer" "TDK"
			(at 0 0 0)
			(layer "B.Fab")
			(hide yes)
			(effects
				(font
					(size 1 1)
					(thickness 0.15)
				)
				(justify mirror)
			)
		)
		(property "Val" "470n"
			(at 0 0 0)
			(layer "B.Fab")
			(hide yes)
			(effects
				(font
					(size 1 1)
					(thickness 0.15)
				)
				(justify mirror)
			)
		)
		(property "Voltage" ""
			(at 0 0 0)
			(layer "B.Fab")
			(hide yes)
			(effects
				(font
					(size 1 1)
					(thickness 0.15)
				)
				(justify mirror)
			)
		)
		(property "DNP" ""
			(at 0 0 0)
			(unlocked yes)
			(layer "B.Fab")
			(hide yes)
			(effects
				(font
					(size 1 1)
					(thickness 0.15)
				)
				(justify mirror)
			)
		)
		(sheetname "/FPGA banks 13-16/")
		(sheetfile "fpga-banks-13-16.kicad_sch")
		(attr smd)
		(fp_rect
			(start -0.925 0.47)
			(end 0.925 -0.47)
			(stroke
				(width 0.05)
				(type default)
			)
			(fill no)
			(layer "B.CrtYd")
		)
		(fp_line
			(start -0.494 -0.248)
			(end -0.494 0.25)
			(stroke
				(width 0.15)
				(type solid)
			)
			(layer "B.Fab")
		)
		(fp_line
			(start -0.494 0.25)
			(end 0.504 0.25)
			(stroke
				(width 0.15)
				(type solid)
			)
			(layer "B.Fab")
		)
		(fp_line
			(start 0.504 -0.248)
			(end -0.494 -0.248)
			(stroke
				(width 0.15)
				(type solid)
			)
			(layer "B.Fab")
		)
		(fp_line
			(start 0.504 0.25)
			(end 0.504 -0.248)
			(stroke
				(width 0.15)
				(type solid)
			)
			(layer "B.Fab")
		)
		(pad "1" smd roundrect
			(at -0.48 0)
			(size 0.59 0.64)
			(layers "B.Cu" "B.Mask" "B.Paste")
			(roundrect_rratio 0.25)
			(net 1 "GND")
			(pintype "passive")
		)
		(pad "2" smd roundrect
			(at 0.48 0)
			(size 0.59 0.64)
			(layers "B.Cu" "B.Mask" "B.Paste")
			(roundrect_rratio 0.25)
			(net 2 "VCC3V3")
			(pintype "passive")
		)
	)
	(footprint "antmicro-footprints:C_0402_1005Metric"
		(layer "B.Cu")
		(at 108.275 112.175 180)
		(descr "Capacitor SMD 0402")
		(tags "capacitor SMD 0402")
		(property "Reference" "C116"
			(at -0.625 0.475 0)
			(layer "B.SilkS")
			(effects
				(font
					(size 0.7 0.7)
					(thickness 0.15)
				)
				(justify left bottom mirror)
			)
		)
		(property "Value" "C_470n_0402"
			(at 0 -1.4 0)
			(layer "B.Fab")
			(effects
				(font
					(size 0.7 0.7)
					(thickness 0.15)
				)
				(justify left bottom mirror)
			)
		)
		(property "Datasheet" "https://product.tdk.com/en/search/capacitor/ceramic/mlcc/info?part_no=C1005X5R1E474M050BB"
			(at 0 0 180)
			(layer "F.Fab")
			(hide yes)
			(effects
				(font
					(size 1.27 1.27)
					(thickness 0.15)
				)
			)
		)
		(property "Description" "SMD Multilayer Ceramic Capacitor, 0.47 µF, 25 V, 0402 [1005 Metric], ± 20%, X5R, C"
			(at 0 0 180)
			(layer "F.Fab")
			(hide yes)
			(effects
				(font
					(size 1.27 1.27)
					(thickness 0.15)
				)
			)
		)
		(property "Author" "Antmicro"
			(at 216.55 224.35 0)
			(layer "B.Fab")
			(hide yes)
			(effects
				(font
					(size 1 1)
					(thickness 0.15)
				)
				(justify mirror)
			)
		)
		(property "Dielectric" ""
			(at 216.55 224.35 0)
			(layer "B.Fab")
			(hide yes)
			(effects
				(font
					(size 1 1)
					(thickness 0.15)
				)
				(justify mirror)
			)
		)
		(property "License" "Apache-2.0"
			(at 216.55 224.35 0)
			(layer "B.Fab")
			(hide yes)
			(effects
				(font
					(size 1 1)
					(thickness 0.15)
				)
				(justify mirror)
			)
		)
		(property "MPN" "C1005X5R1E474M050BB"
			(at 216.55 224.35 0)
			(layer "B.Fab")
			(hide yes)
			(effects
				(font
					(size 1 1)
					(thickness 0.15)
				)
				(justify mirror)
			)
		)
		(property "Manufacturer" "TDK"
			(at 216.55 224.35 0)
			(layer "B.Fab")
			(hide yes)
			(effects
				(font
					(size 1 1)
					(thickness 0.15)
				)
				(justify mirror)
			)
		)
		(property "Val" "470n"
			(at 216.55 224.35 0)
			(layer "B.Fab")
			(hide yes)
			(effects
				(font
					(size 1 1)
					(thickness 0.15)
				)
				(justify mirror)
			)
		)
		(property "Voltage" ""
			(at 216.55 224.35 0)
			(layer "B.Fab")
			(hide yes)
			(effects
				(font
					(size 1 1)
					(thickness 0.15)
				)
				(justify mirror)
			)
		)
		(property "DNP" ""
			(at 0 0 180)
			(unlocked yes)
			(layer "B.Fab")
			(hide yes)
			(effects
				(font
					(size 1 1)
					(thickness 0.15)
				)
				(justify mirror)
			)
		)
		(sheetname "/FPGA banks 13-16/")
		(sheetfile "fpga-banks-13-16.kicad_sch")
		(attr smd)
		(fp_rect
			(start -0.925 0.47)
			(end 0.925 -0.47)
			(stroke
				(width 0.05)
				(type default)
			)
			(fill no)
			(layer "B.CrtYd")
		)
		(fp_line
			(start 0.504 0.25)
			(end 0.504 -0.248)
			(stroke
				(width 0.15)
				(type solid)
			)
			(layer "B.Fab")
		)
		(fp_line
			(start 0.504 -0.248)
			(end -0.494 -0.248)
			(stroke
				(width 0.15)
				(type solid)
			)
			(layer "B.Fab")
		)
		(fp_line
			(start -0.494 0.25)
			(end 0.504 0.25)
			(stroke
				(width 0.15)
				(type solid)
			)
			(layer "B.Fab")
		)
		(fp_line
			(start -0.494 -0.248)
			(end -0.494 0.25)
			(stroke
				(width 0.15)
				(type solid)
			)
			(layer "B.Fab")
		)
		(pad "1" smd roundrect
			(at -0.48 0 180)
			(size 0.59 0.64)
			(layers "B.Cu" "B.Mask" "B.Paste")
			(roundrect_rratio 0.25)
			(net 1 "GND")
			(pintype "passive")
		)
		(pad "2" smd roundrect
			(at 0.48 0 180)
			(size 0.59 0.64)
			(layers "B.Cu" "B.Mask" "B.Paste")
			(roundrect_rratio 0.25)
			(net 2 "VCC3V3")
			(pintype "passive")
		)
	)
	(footprint "antmicro-footprints:C_0402_1005Metric"
		(layer "B.Cu")
		(at 103.775 109.975 180)
		(descr "Capacitor SMD 0402")
		(tags "capacitor SMD 0402")
		(property "Reference" "C122"
			(at -1.425 0.575 0)
			(layer "B.SilkS")
			(effects
				(font
					(size 0.7 0.7)
					(thickness 0.15)
				)
				(justify left bottom mirror)
			)
		)
		(property "Value" "C_470n_0402"
			(at 0 -1.4 0)
			(layer "B.Fab")
			(effects
				(font
					(size 0.7 0.7)
					(thickness 0.15)
				)
				(justify left bottom mirror)
			)
		)
		(property "Datasheet" "https://product.tdk.com/en/search/capacitor/ceramic/mlcc/info?part_no=C1005X5R1E474M050BB"
			(at 0 0 180)
			(layer "F.Fab")
			(hide yes)
			(effects
				(font
					(size 1.27 1.27)
					(thickness 0.15)
				)
			)
		)
		(property "Description" "SMD Multilayer Ceramic Capacitor, 0.47 µF, 25 V, 0402 [1005 Metric], ± 20%, X5R, C"
			(at 0 0 180)
			(layer "F.Fab")
			(hide yes)
			(effects
				(font
					(size 1.27 1.27)
					(thickness 0.15)
				)
			)
		)
		(property "Author" "Antmicro"
			(at 207.55 219.95 0)
			(layer "B.Fab")
			(hide yes)
			(effects
				(font
					(size 1 1)
					(thickness 0.15)
				)
				(justify mirror)
			)
		)
		(property "Dielectric" ""
			(at 207.55 219.95 0)
			(layer "B.Fab")
			(hide yes)
			(effects
				(font
					(size 1 1)
					(thickness 0.15)
				)
				(justify mirror)
			)
		)
		(property "License" "Apache-2.0"
			(at 207.55 219.95 0)
			(layer "B.Fab")
			(hide yes)
			(effects
				(font
					(size 1 1)
					(thickness 0.15)
				)
				(justify mirror)
			)
		)
		(property "MPN" "C1005X5R1E474M050BB"
			(at 207.55 219.95 0)
			(layer "B.Fab")
			(hide yes)
			(effects
				(font
					(size 1 1)
					(thickness 0.15)
				)
				(justify mirror)
			)
		)
		(property "Manufacturer" "TDK"
			(at 207.55 219.95 0)
			(layer "B.Fab")
			(hide yes)
			(effects
				(font
					(size 1 1)
					(thickness 0.15)
				)
				(justify mirror)
			)
		)
		(property "Val" "470n"
			(at 207.55 219.95 0)
			(layer "B.Fab")
			(hide yes)
			(effects
				(font
					(size 1 1)
					(thickness 0.15)
				)
				(justify mirror)
			)
		)
		(property "Voltage" ""
			(at 207.55 219.95 0)
			(layer "B.Fab")
			(hide yes)
			(effects
				(font
					(size 1 1)
					(thickness 0.15)
				)
				(justify mirror)
			)
		)
		(property "DNP" ""
			(at 0 0 180)
			(unlocked yes)
			(layer "B.Fab")
			(hide yes)
			(effects
				(font
					(size 1 1)
					(thickness 0.15)
				)
				(justify mirror)
			)
		)
		(sheetname "/FPGA banks 13-16/")
		(sheetfile "fpga-banks-13-16.kicad_sch")
		(attr smd)
		(fp_rect
			(start -0.925 0.47)
			(end 0.925 -0.47)
			(stroke
				(width 0.05)
				(type default)
			)
			(fill no)
			(layer "B.CrtYd")
		)
		(fp_line
			(start 0.504 0.25)
			(end 0.504 -0.248)
			(stroke
				(width 0.15)
				(type solid)
			)
			(layer "B.Fab")
		)
		(fp_line
			(start 0.504 -0.248)
			(end -0.494 -0.248)
			(stroke
				(width 0.15)
				(type solid)
			)
			(layer "B.Fab")
		)
		(fp_line
			(start -0.494 0.25)
			(end 0.504 0.25)
			(stroke
				(width 0.15)
				(type solid)
			)
			(layer "B.Fab")
		)
		(fp_line
			(start -0.494 -0.248)
			(end -0.494 0.25)
			(stroke
				(width 0.15)
				(type solid)
			)
			(layer "B.Fab")
		)
		(pad "1" smd roundrect
			(at -0.48 0 180)
			(size 0.59 0.64)
			(layers "B.Cu" "B.Mask" "B.Paste")
			(roundrect_rratio 0.25)
			(net 1 "GND")
			(pintype "passive")
		)
		(pad "2" smd roundrect
			(at 0.48 0 180)
			(size 0.59 0.64)
			(layers "B.Cu" "B.Mask" "B.Paste")
			(roundrect_rratio 0.25)
			(net 2 "VCC3V3")
			(pintype "passive")
		)
	)
)
